(kicad_pcb
	(version 20260206)
	(generator "pcbnew")
	(generator_version "10.0")
	(general
		(thickness 1.6)
		(legacy_teardrops no)
	)
	(paper "A4")
	(title_block
		(title "Wiwynn_Tioga_Pass_MB.brd")
		(comment 1 "Tioga Pass / footprint 865 of 4770 (CONX8), pads 1-64 of 64")
	)
	(layers
		(0 "F.Cu" signal "TOP")
		(4 "In1.Cu" signal "L2GND")
		(6 "In2.Cu" signal "L3")
		(8 "In3.Cu" signal "L4GND")
		(10 "In4.Cu" signal "L5")
		(12 "In5.Cu" signal "L6GND")
		(14 "In6.Cu" signal "L7VCC")
		(16 "In7.Cu" signal "L8VCC")
		(18 "In8.Cu" signal "L9GND")
		(20 "In9.Cu" signal "L10")
		(22 "In10.Cu" signal "L11GND")
		(24 "In11.Cu" signal "L12")
		(26 "In12.Cu" signal "L13GND")
		(2 "B.Cu" signal "BOTTOM")
		(9 "F.Adhes" user "F.Adhesive")
		(11 "B.Adhes" user "B.Adhesive")
		(13 "F.Paste" user "Package Geometry/Pastemask Top")
		(15 "B.Paste" user "Package Geometry/Pastemask Bottom")
		(5 "F.SilkS" user "Ref Des/Silkscreen Top")
		(7 "B.SilkS" user "Ref Des/Silkscreen Bottom")
		(1 "F.Mask" user "Board Geometry/Soldermask Top")
		(3 "B.Mask" user "Board Geometry/Soldermask Bottom")
		(17 "Dwgs.User" user "User.Drawings")
		(19 "Cmts.User" user "User.Comments")
		(21 "Eco1.User" user "User.Eco1")
		(23 "Eco2.User" user "User.Eco2")
		(25 "Edge.Cuts" user "Board Geometry/Outline")
		(27 "Margin" user)
		(31 "F.CrtYd" user "Package Geometry/Place Bound Top")
		(29 "B.CrtYd" user "Package Geometry/Place Bound Bottom")
		(35 "F.Fab" user "Ref Des/Assembly Top")
		(33 "B.Fab" user "Ref Des/Assembly Bottom")
	)
	(footprint ""
		(layer "F.Cu")
		(at 369.085114 -6.089904 180)
		(property "Reference" "CONX8"
			(at 0 0 180)
			(layer "F.SilkS")
			(hide yes)
			(effects
				(font
					(size 1.27 1.27)
				)
			)
		)
		(property "Value" "*"
			(at -14.3129 -7.5565 180)
			(unlocked yes)
			(layer "F.Fab")
			(hide yes)
			(effects
				(font
					(size 1.27 1.016)
					(thickness 0.1524)
				)
			)
		)
		(property "Device Type" "SMC-CONN60A-22-GP_CONN-G7-SMC-A"
			(at -14.3129 -9.0805 180)
			(unlocked yes)
			(layer "F.Fab")
			(hide yes)
			(effects
				(font
					(size 1.27 1.016)
					(thickness 0.1524)
				)
			)
		)
		(duplicate_pad_numbers_are_jumpers no)
		(pad "" np_thru_hole circle
			(at -13.10005 1.500124 180)
			(size 0.254 0.254)
			(drill 1.27)
			(layers "*.Cu" "*.Mask")
			(clearance 0.8636)
			(thermal_gap 0.8636)
		)
		(pad "" np_thru_hole circle
			(at 13.10005 0 180)
			(size 0.254 0.254)
			(drill 1.27)
			(layers "*.Cu" "*.Mask")
			(clearance 0.8636)
			(thermal_gap 0.8636)
		)
		(pad "1" smd rect
			(at -11.599926 1.700022 180)
			(size 0.508 1.1938)
			(layers "F.Cu" "F.Mask" "F.Paste")
			(net "GND")
		)
		(pad "2" smd rect
			(at -11.599926 -1.700022 180)
			(size 0.508 1.1938)
			(layers "F.Cu" "F.Mask" "F.Paste")
			(net "Net_545")
		)
		(pad "3" smd rect
			(at -10.80008 1.700022 180)
			(size 0.508 1.1938)
			(layers "F.Cu" "F.Mask" "F.Paste")
			(net "P3E_CPU0_PE2_SS_C_TXN<8>")
		)
		(pad "4" smd rect
			(at -10.80008 -1.700022 180)
			(size 0.508 1.1938)
			(layers "F.Cu" "F.Mask" "F.Paste")
			(net "GND")
		)
		(pad "5" smd rect
			(at -9.99998 1.700022 180)
			(size 0.508 1.1938)
			(layers "F.Cu" "F.Mask" "F.Paste")
			(net "P3E_CPU0_PE2_SS_C_TXP<8>")
		)
		(pad "6" smd rect
			(at -9.99998 -1.700022 180)
			(size 0.508 1.1938)
			(layers "F.Cu" "F.Mask" "F.Paste")
			(net "P3E_CPU0_PE2_SS_RXN<8>")
		)
		(pad "7" smd rect
			(at -9.19988 1.700022 180)
			(size 0.508 1.1938)
			(layers "F.Cu" "F.Mask" "F.Paste")
			(net "GND")
		)
		(pad "8" smd rect
			(at -9.19988 -1.700022 180)
			(size 0.508 1.1938)
			(layers "F.Cu" "F.Mask" "F.Paste")
			(net "P3E_CPU0_PE2_SS_RXP<8>")
		)
		(pad "9" smd rect
			(at -8.400034 1.700022 180)
			(size 0.508 1.1938)
			(layers "F.Cu" "F.Mask" "F.Paste")
			(net "P3E_CPU0_PE2_SS_C_TXN<9>")
		)
		(pad "10" smd rect
			(at -8.400034 -1.700022 180)
			(size 0.508 1.1938)
			(layers "F.Cu" "F.Mask" "F.Paste")
			(net "GND")
		)
		(pad "11" smd rect
			(at -7.599934 1.700022 180)
			(size 0.508 1.1938)
			(layers "F.Cu" "F.Mask" "F.Paste")
			(net "P3E_CPU0_PE2_SS_C_TXP<9>")
		)
		(pad "12" smd rect
			(at -7.599934 -1.700022 180)
			(size 0.508 1.1938)
			(layers "F.Cu" "F.Mask" "F.Paste")
			(net "P3E_CPU0_PE2_SS_RXN<9>")
		)
		(pad "13" smd rect
			(at -6.800088 1.700022 180)
			(size 0.508 1.1938)
			(layers "F.Cu" "F.Mask" "F.Paste")
			(net "GND")
		)
		(pad "14" smd rect
			(at -6.800088 -1.700022 180)
			(size 0.508 1.1938)
			(layers "F.Cu" "F.Mask" "F.Paste")
			(net "P3E_CPU0_PE2_SS_RXP<9>")
		)
		(pad "15" smd rect
			(at -5.999988 1.700022 180)
			(size 0.508 1.1938)
			(layers "F.Cu" "F.Mask" "F.Paste")
			(net "P3E_CPU0_PE2_SS_C_TXN<10>")
		)
		(pad "16" smd rect
			(at -5.999988 -1.700022 180)
			(size 0.508 1.1938)
			(layers "F.Cu" "F.Mask" "F.Paste")
			(net "GND")
		)
		(pad "17" smd rect
			(at -5.199888 1.700022 180)
			(size 0.508 1.1938)
			(layers "F.Cu" "F.Mask" "F.Paste")
			(net "P3E_CPU0_PE2_SS_C_TXP<10>")
		)
		(pad "18" smd rect
			(at -5.199888 -1.700022 180)
			(size 0.508 1.1938)
			(layers "F.Cu" "F.Mask" "F.Paste")
			(net "P3E_CPU0_PE2_SS_RXN<10>")
		)
		(pad "19" smd rect
			(at -4.400042 1.700022 180)
			(size 0.508 1.1938)
			(layers "F.Cu" "F.Mask" "F.Paste")
			(net "GND")
		)
		(pad "20" smd rect
			(at -4.400042 -1.700022 180)
			(size 0.508 1.1938)
			(layers "F.Cu" "F.Mask" "F.Paste")
			(net "P3E_CPU0_PE2_SS_RXP<10>")
		)
		(pad "21" smd rect
			(at -3.599942 1.700022 180)
			(size 0.508 1.1938)
			(layers "F.Cu" "F.Mask" "F.Paste")
			(net "P3E_CPU0_PE2_SS_C_TXP<11>")
		)
		(pad "22" smd rect
			(at -3.599942 -1.700022 180)
			(size 0.508 1.1938)
			(layers "F.Cu" "F.Mask" "F.Paste")
			(net "GND")
		)
		(pad "23" smd rect
			(at -2.800096 1.700022 180)
			(size 0.508 1.1938)
			(layers "F.Cu" "F.Mask" "F.Paste")
			(net "P3E_CPU0_PE2_SS_C_TXN<11>")
		)
		(pad "24" smd rect
			(at -2.800096 -1.700022 180)
			(size 0.508 1.1938)
			(layers "F.Cu" "F.Mask" "F.Paste")
			(net "P3E_CPU0_PE2_SS_RXN<11>")
		)
		(pad "25" smd rect
			(at -1.999996 1.700022 180)
			(size 0.508 1.1938)
			(layers "F.Cu" "F.Mask" "F.Paste")
			(net "GND")
		)
		(pad "26" smd rect
			(at -1.999996 -1.700022 180)
			(size 0.508 1.1938)
			(layers "F.Cu" "F.Mask" "F.Paste")
			(net "P3E_CPU0_PE2_SS_RXP<11>")
		)
		(pad "27" smd rect
			(at -1.199896 1.700022 180)
			(size 0.508 1.1938)
			(layers "F.Cu" "F.Mask" "F.Paste")
			(net "P3E_CPU0_PE2_SS_C_TXN<12>")
		)
		(pad "28" smd rect
			(at -1.199896 -1.700022 180)
			(size 0.508 1.1938)
			(layers "F.Cu" "F.Mask" "F.Paste")
			(net "GND")
		)
		(pad "29" smd rect
			(at -0.40005 1.700022 180)
			(size 0.508 1.1938)
			(layers "F.Cu" "F.Mask" "F.Paste")
			(net "P3E_CPU0_PE2_SS_C_TXP<12>")
		)
		(pad "30" smd rect
			(at -0.40005 -1.700022 180)
			(size 0.508 1.1938)
			(layers "F.Cu" "F.Mask" "F.Paste")
			(net "P3E_CPU0_PE2_SS_RXN<12>")
		)
		(pad "31" smd rect
			(at 0.40005 1.700022 180)
			(size 0.508 1.1938)
			(layers "F.Cu" "F.Mask" "F.Paste")
			(net "GND")
		)
		(pad "32" smd rect
			(at 0.40005 -1.700022 180)
			(size 0.508 1.1938)
			(layers "F.Cu" "F.Mask" "F.Paste")
			(net "P3E_CPU0_PE2_SS_RXP<12>")
		)
		(pad "33" smd rect
			(at 1.199896 1.700022 180)
			(size 0.508 1.1938)
			(layers "F.Cu" "F.Mask" "F.Paste")
			(net "P3E_CPU0_PE2_SS_C_TXN<13>")
		)
		(pad "34" smd rect
			(at 1.199896 -1.700022 180)
			(size 0.508 1.1938)
			(layers "F.Cu" "F.Mask" "F.Paste")
			(net "GND")
		)
		(pad "35" smd rect
			(at 1.999996 1.700022 180)
			(size 0.508 1.1938)
			(layers "F.Cu" "F.Mask" "F.Paste")
			(net "P3E_CPU0_PE2_SS_C_TXP<13>")
		)
		(pad "36" smd rect
			(at 1.999996 -1.700022 180)
			(size 0.508 1.1938)
			(layers "F.Cu" "F.Mask" "F.Paste")
			(net "P3E_CPU0_PE2_SS_RXP<13>")
		)
		(pad "37" smd rect
			(at 2.800096 1.700022 180)
			(size 0.508 1.1938)
			(layers "F.Cu" "F.Mask" "F.Paste")
			(net "GND")
		)
		(pad "38" smd rect
			(at 2.800096 -1.700022 180)
			(size 0.508 1.1938)
			(layers "F.Cu" "F.Mask" "F.Paste")
			(net "P3E_CPU0_PE2_SS_RXN<13>")
		)
		(pad "39" smd rect
			(at 3.599942 1.700022 180)
			(size 0.508 1.1938)
			(layers "F.Cu" "F.Mask" "F.Paste")
			(net "P3E_CPU0_PE2_SS_C_TXP<14>")
		)
		(pad "40" smd rect
			(at 3.599942 -1.700022 180)
			(size 0.508 1.1938)
			(layers "F.Cu" "F.Mask" "F.Paste")
			(net "GND")
		)
		(pad "41" smd rect
			(at 4.400042 1.700022 180)
			(size 0.508 1.1938)
			(layers "F.Cu" "F.Mask" "F.Paste")
			(net "P3E_CPU0_PE2_SS_C_TXN<14>")
		)
		(pad "42" smd rect
			(at 4.400042 -1.700022 180)
			(size 0.508 1.1938)
			(layers "F.Cu" "F.Mask" "F.Paste")
			(net "P3E_CPU0_PE2_SS_RXN<14>")
		)
		(pad "43" smd rect
			(at 5.199888 1.700022 180)
			(size 0.508 1.1938)
			(layers "F.Cu" "F.Mask" "F.Paste")
			(net "GND")
		)
		(pad "44" smd rect
			(at 5.199888 -1.700022 180)
			(size 0.508 1.1938)
			(layers "F.Cu" "F.Mask" "F.Paste")
			(net "P3E_CPU0_PE2_SS_RXP<14>")
		)
		(pad "45" smd rect
			(at 5.999988 1.700022 180)
			(size 0.508 1.1938)
			(layers "F.Cu" "F.Mask" "F.Paste")
			(net "P3E_CPU0_PE2_SS_C_TXN<15>")
		)
		(pad "46" smd rect
			(at 5.999988 -1.700022 180)
			(size 0.508 1.1938)
			(layers "F.Cu" "F.Mask" "F.Paste")
			(net "GND")
		)
		(pad "47" smd rect
			(at 6.800088 1.700022 180)
			(size 0.508 1.1938)
			(layers "F.Cu" "F.Mask" "F.Paste")
			(net "P3E_CPU0_PE2_SS_C_TXP<15>")
		)
		(pad "48" smd rect
			(at 6.800088 -1.700022 180)
			(size 0.508 1.1938)
			(layers "F.Cu" "F.Mask" "F.Paste")
			(net "P3E_CPU0_PE2_SS_RXN<15>")
		)
		(pad "49" smd rect
			(at 7.599934 1.700022 180)
			(size 0.508 1.1938)
			(layers "F.Cu" "F.Mask" "F.Paste")
			(net "GND")
		)
		(pad "50" smd rect
			(at 7.599934 -1.700022 180)
			(size 0.508 1.1938)
			(layers "F.Cu" "F.Mask" "F.Paste")
			(net "P3E_CPU0_PE2_SS_RXP<15>")
		)
		(pad "51" smd rect
			(at 8.400034 1.700022 180)
			(size 0.508 1.1938)
			(layers "F.Cu" "F.Mask" "F.Paste")
			(net "JTAG_RISER_TDI")
		)
		(pad "52" smd rect
			(at 8.400034 -1.700022 180)
			(size 0.508 1.1938)
			(layers "F.Cu" "F.Mask" "F.Paste")
			(net "GND")
		)
		(pad "53" smd rect
			(at 9.19988 1.700022 180)
			(size 0.508 1.1938)
			(layers "F.Cu" "F.Mask" "F.Paste")
			(net "JTAG_RISER_TDO")
		)
		(pad "54" smd rect
			(at 9.19988 -1.700022 180)
			(size 0.508 1.1938)
			(layers "F.Cu" "F.Mask" "F.Paste")
			(net "JTAG_RISER_TMS")
		)
		(pad "55" smd rect
			(at 9.99998 1.700022 180)
			(size 0.508 1.1938)
			(layers "F.Cu" "F.Mask" "F.Paste")
			(net "GND")
		)
		(pad "56" smd rect
			(at 9.99998 -1.700022 180)
			(size 0.508 1.1938)
			(layers "F.Cu" "F.Mask" "F.Paste")
			(net "JTAG_RISER_TCK")
		)
		(pad "57" smd rect
			(at 10.80008 1.700022 180)
			(size 0.508 1.1938)
			(layers "F.Cu" "F.Mask" "F.Paste")
			(net "USB2_P02_DN")
		)
		(pad "58" smd rect
			(at 10.80008 -1.700022 180)
			(size 0.508 1.1938)
			(layers "F.Cu" "F.Mask" "F.Paste")
			(net "GND")
		)
		(pad "59" smd rect
			(at 11.599926 1.700022 180)
			(size 0.508 1.1938)
			(layers "F.Cu" "F.Mask" "F.Paste")
			(net "USB2_P02_DP")
		)
		(pad "60" smd rect
			(at 11.599926 -1.700022 180)
			(size 0.508 1.1938)
			(layers "F.Cu" "F.Mask" "F.Paste")
			(net "JTAG_RISER_TRST")
		)
		(pad "PTH1" thru_hole circle
			(at -15.450058 0 180)
			(size 1.27 1.27)
			(drill 0.8636)
			(layers "*.Cu" "*.Mask")
			(remove_unused_layers no)
			(net "GND")
			(clearance 0.1524)
			(thermal_gap 0.1524)
		)
		(pad "PTH2" thru_hole circle
			(at 15.450058 0 180)
			(size 1.27 1.27)
			(drill 0.8636)
			(layers "*.Cu" "*.Mask")
			(remove_unused_layers no)
			(net "GND")
			(clearance 0.1524)
			(thermal_gap 0.1524)
		)
	)
)
